# S9S_MB_2U (Grand Teton) — schematic netlist excerpt (pin names and nets, part order shuffled) for the footprints in the layout excerpt that follows; sources: Cadence DE-HDL packaged netlist, KiCad conversion of 03242023_DA0F0TMBIJ0_F0T_Motherboard_J_brd_V01_OCP.brd

Q132  MOSFET_NCH_DUAL  PJT138K IC  pkg SOT363XD  page 146
  S1  = GND
  G1  = PRSNT_CABLE_GPU_B3_N
  D2  = PRSNT_CABLE_GPU_B3_ISO_N
  S2  = GND
  G2  = PRSNT_CABLE_GPU_B3
  D1  = PRSNT_CABLE_GPU_B3

PR560  Q_RES  100 1% CHIP  pkg 0402LF  page 284 : A = VSENSE_PVCCFA_EHV_FIVRA_CPU1_DN ; B = GND

(kicad_pcb
	(version 20260206)
	(generator "pcbnew")
	(generator_version "10.0")
	(general
		(thickness 1.6)
		(legacy_teardrops no)
	)
	(paper "A4")
	(title_block
		(title "03242023_DA0F0TMBIJ0_F0T_Motherboard_J_brd_V01_OCP.brd")
		(comment 1 "Grand Teton / footprints 2716-2717 of 6105")
	)
	(layers
		(0 "F.Cu" signal "TOP")
		(4 "In1.Cu" signal "GND")
		(6 "In2.Cu" signal "IN1")
		(8 "In3.Cu" signal "GND1")
		(10 "In4.Cu" signal "IN2")
		(12 "In5.Cu" signal "GND2")
		(14 "In6.Cu" signal "IN3")
		(16 "In7.Cu" signal "GND3")
		(18 "In8.Cu" signal "VCC")
		(20 "In9.Cu" signal "VCC1")
		(22 "In10.Cu" signal "GND4")
		(24 "In11.Cu" signal "IN4")
		(26 "In12.Cu" signal "GND5")
		(28 "In13.Cu" signal "IN5")
		(30 "In14.Cu" signal "GND6")
		(32 "In15.Cu" signal "IN6")
		(34 "In16.Cu" signal "GND7")
		(2 "B.Cu" signal "BOTTOM")
		(9 "F.Adhes" user "F.Adhesive")
		(11 "B.Adhes" user "B.Adhesive")
		(13 "F.Paste" user "Package Geometry/Pastemask Top")
		(15 "B.Paste" user "Package Geometry/Pastemask Bottom")
		(5 "F.SilkS" user "Ref Des/Silkscreen Top")
		(7 "B.SilkS" user "Ref Des/Silkscreen Bottom")
		(1 "F.Mask" user "Board Geometry/Soldermask Top")
		(3 "B.Mask" user "Board Geometry/Soldermask Bottom")
		(17 "Dwgs.User" user "User.Drawings")
		(19 "Cmts.User" user "User.Comments")
		(21 "Eco1.User" user "User.Eco1")
		(23 "Eco2.User" user "User.Eco2")
		(25 "Edge.Cuts" user "Board Geometry/Outline")
		(27 "Margin" user)
		(31 "F.CrtYd" user "Package Geometry/Place Bound Top")
		(29 "B.CrtYd" user "Package Geometry/Place Bound Bottom")
		(35 "F.Fab" user "Ref Des/Assembly Top")
		(33 "B.Fab" user "Ref Des/Assembly Bottom")
	)
	(footprint ""
		(layer "F.Cu")
		(at 300.54042 -424.00601 90)
		(property "Reference" "Q132"
			(at -7.76986 7.383272 90)
			(unlocked yes)
			(layer "F.SilkS")
			(effects
				(font
					(size 0.7874 0.5842)
					(thickness 0.1524)
				)
				(justify left)
			)
		)
		(property "Value" ""
			(at 0 0 90)
			(layer "F.Fab")
			(effects
				(font
					(size 1.27 1.27)
				)
			)
		)
		(duplicate_pad_numbers_are_jumpers no)
		(fp_line
			(start 1.332738 -1.100074)
			(end 1.332738 1.100074)
			(stroke
				(width 0.1524)
				(type default)
			)
			(layer "F.SilkS")
		)
		(fp_line
			(start 0.4826 -1.100074)
			(end 1.332738 -1.100074)
			(stroke
				(width 0.1524)
				(type default)
			)
			(layer "F.SilkS")
		)
		(fp_line
			(start -0.4826 -1.100074)
			(end 0 -0.541274)
			(stroke
				(width 0.1524)
				(type default)
			)
			(layer "F.SilkS")
		)
		(fp_line
			(start -1.332738 -1.100074)
			(end -0.4826 -1.100074)
			(stroke
				(width 0.1524)
				(type default)
			)
			(layer "F.SilkS")
		)
		(fp_line
			(start 0 -0.541274)
			(end 0.4826 -1.100074)
			(stroke
				(width 0.1524)
				(type default)
			)
			(layer "F.SilkS")
		)
		(fp_line
			(start 1.332738 1.100074)
			(end -1.332738 1.100074)
			(stroke
				(width 0.1524)
				(type default)
			)
			(layer "F.SilkS")
		)
		(fp_line
			(start -1.332738 1.100074)
			(end -1.332738 -1.100074)
			(stroke
				(width 0.1524)
				(type default)
			)
			(layer "F.SilkS")
		)
		(fp_poly
			(pts
				(xy -2.37998 -1.432814) (xy -1.677924 -1.081786) (xy -2.37998 -0.730758)
			)
			(stroke
				(width 0)
				(type default)
			)
			(fill yes)
			(layer "F.SilkS")
		)
		(fp_line
			(start 0.674878 -1.100074)
			(end 0.674878 1.100074)
			(stroke
				(width 0.1)
				(type default)
			)
			(layer "F.Fab")
		)
		(fp_line
			(start -0.674878 -1.100074)
			(end 0.674878 -1.100074)
			(stroke
				(width 0.1)
				(type default)
			)
			(layer "F.Fab")
		)
		(fp_line
			(start 0.674878 1.100074)
			(end -0.674878 1.100074)
			(stroke
				(width 0.1)
				(type default)
			)
			(layer "F.Fab")
		)
		(fp_line
			(start -0.674878 1.100074)
			(end -0.674878 -1.100074)
			(stroke
				(width 0.1)
				(type default)
			)
			(layer "F.Fab")
		)
		(fp_poly
			(pts
				(xy -2.2352 -0.298958) (xy -2.2352 -1.001014) (xy -1.533144 -0.649986)
			)
			(stroke
				(width 0)
				(type default)
			)
			(fill yes)
			(layer "F.Fab")
		)
		(pad "1" smd rect
			(at -0.94996 -0.649986 180)
			(size 0.4318 0.508)
			(layers "F.Cu" "F.Mask" "F.Paste")
			(net "GND")
		)
		(pad "2" smd rect
			(at -0.94996 0 180)
			(size 0.4318 0.508)
			(layers "F.Cu" "F.Mask" "F.Paste")
			(net "PRSNT_CABLE_GPU_B3_N")
		)
		(pad "3" smd rect
			(at -0.94996 0.649986 180)
			(size 0.4318 0.508)
			(layers "F.Cu" "F.Mask" "F.Paste")
			(net "PRSNT_CABLE_GPU_B3_ISO_N")
		)
		(pad "4" smd rect
			(at 0.94996 0.649986 180)
			(size 0.4318 0.508)
			(layers "F.Cu" "F.Mask" "F.Paste")
			(net "GND")
		)
		(pad "5" smd rect
			(at 0.94996 0 180)
			(size 0.4318 0.508)
			(layers "F.Cu" "F.Mask" "F.Paste")
			(net "PRSNT_CABLE_GPU_B3")
		)
		(pad "6" smd rect
			(at 0.94996 -0.649986 180)
			(size 0.4318 0.508)
			(layers "F.Cu" "F.Mask" "F.Paste")
			(net "PRSNT_CABLE_GPU_B3")
		)
	)
	(footprint ""
		(layer "F.Cu")
		(at 56.950102 -336.006186 180)
		(property "Reference" "PR560"
			(at 0 0 180)
			(layer "F.SilkS")
			(hide yes)
			(effects
				(font
					(size 1.27 1.27)
				)
			)
		)
		(property "Value" ""
			(at 0 0 180)
			(layer "F.Fab")
			(effects
				(font
					(size 1.27 1.27)
				)
			)
		)
		(duplicate_pad_numbers_are_jumpers no)
		(fp_line
			(start 0.7874 0.4064)
			(end -0.7874 0.4064)
			(stroke
				(width 0.1524)
				(type default)
			)
			(layer "F.SilkS")
		)
		(fp_line
			(start 0.7874 -0.4064)
			(end 0.7874 0.4064)
			(stroke
				(width 0.1524)
				(type default)
			)
			(layer "F.SilkS")
		)
		(fp_line
			(start -0.7874 0.4064)
			(end -0.7874 -0.4064)
			(stroke
				(width 0.1524)
				(type default)
			)
			(layer "F.SilkS")
		)
		(fp_line
			(start -0.7874 -0.4064)
			(end 0.7874 -0.4064)
			(stroke
				(width 0.1524)
				(type default)
			)
			(layer "F.SilkS")
		)
		(fp_line
			(start 0.67945 0.3048)
			(end 0.120396 0.3048)
			(stroke
				(width 0.1)
				(type default)
			)
			(layer "F.Fab")
		)
		(fp_line
			(start 0.67945 -0.3048)
			(end 0.67945 0.3048)
			(stroke
				(width 0.1)
				(type default)
			)
			(layer "F.Fab")
		)
		(fp_line
			(start 0.12065 -0.2794)
			(end 0.12065 -0.3048)
			(stroke
				(width 0.1)
				(type default)
			)
			(layer "F.Fab")
		)
		(fp_line
			(start 0.12065 -0.3048)
			(end 0.67945 -0.3048)
			(stroke
				(width 0.1)
				(type default)
			)
			(layer "F.Fab")
		)
		(fp_line
			(start 0.120396 0.3048)
			(end 0.120396 0.2794)
			(stroke
				(width 0.1)
				(type default)
			)
			(layer "F.Fab")
		)
		(fp_line
			(start 0.120396 0.2794)
			(end -0.12065 0.2794)
			(stroke
				(width 0.1)
				(type default)
			)
			(layer "F.Fab")
		)
		(fp_line
			(start -0.12065 0.3048)
			(end -0.67945 0.3048)
			(stroke
				(width 0.1)
				(type default)
			)
			(layer "F.Fab")
		)
		(fp_line
			(start -0.12065 0.2794)
			(end -0.12065 0.3048)
			(stroke
				(width 0.1)
				(type default)
			)
			(layer "F.Fab")
		)
		(fp_line
			(start -0.12065 -0.2794)
			(end 0.12065 -0.2794)
			(stroke
				(width 0.1)
				(type default)
			)
			(layer "F.Fab")
		)
		(fp_line
			(start -0.12065 -0.305054)
			(end -0.12065 -0.2794)
			(stroke
				(width 0.1)
				(type default)
			)
			(layer "F.Fab")
		)
		(fp_line
			(start -0.67945 0.3048)
			(end -0.67945 -0.305054)
			(stroke
				(width 0.1)
				(type default)
			)
			(layer "F.Fab")
		)
		(fp_line
			(start -0.67945 -0.305054)
			(end -0.12065 -0.305054)
			(stroke
				(width 0.1)
				(type default)
			)
			(layer "F.Fab")
		)
		(pad "1" smd circle
			(at -0.40005 0 180)
			(size 0 0)
			(layers "F.Cu" "F.Mask" "F.Paste")
			(net "VSENSE_PVCCFA_EHV_FIVRA_CPU1_DN")
		)
		(pad "2" smd circle
			(at 0.40005 0 180)
			(size 0 0)
			(layers "F.Cu" "F.Mask" "F.Paste")
			(net "GND")
		)
	)
)
